# T6G (Grand Teton) — schematic netlist excerpt (pin names and nets, part order shuffled) for the footprints in the layout excerpt that follows; sources: Cadence DE-HDL packaged netlist, KiCad conversion of 04192023_DAF0TMB3IC0_F0TG_MB_C_brd_V02_OCP.brd

R561  Q_RES  0 5% CHIP  pkg 0402LF  page 134 : A = P12V_OCP_SFF_BUF_EN_R ; B = P12V_OCP_EN_1_R
R1494  Q_RES  33 5% CHIP  pkg 0402LF  page 151 : A = SMB_VR_3V3STBY_SDA ; B = SMB_SCM_2_R1_SDA

(kicad_pcb
	(version 20260206)
	(generator "pcbnew")
	(generator_version "10.0")
	(general
		(thickness 1.6)
		(legacy_teardrops no)
	)
	(paper "A4")
	(title_block
		(title "04192023_DAF0TMB3IC0_F0TG_MB_C_brd_V02_OCP.brd")
		(comment 1 "Grand Teton / footprints 1854-1855 of 8354")
	)
	(layers
		(0 "F.Cu" signal "TOP")
		(4 "In1.Cu" signal "GND")
		(6 "In2.Cu" signal "IN1")
		(8 "In3.Cu" signal "GND1")
		(10 "In4.Cu" signal "IN2")
		(12 "In5.Cu" signal "GND2")
		(14 "In6.Cu" signal "IN3")
		(16 "In7.Cu" signal "GND3")
		(18 "In8.Cu" signal "VCC")
		(20 "In9.Cu" signal "VCC1")
		(22 "In10.Cu" signal "GND4")
		(24 "In11.Cu" signal "IN4")
		(26 "In12.Cu" signal "GND5")
		(28 "In13.Cu" signal "IN5")
		(30 "In14.Cu" signal "GND6")
		(32 "In15.Cu" signal "IN6")
		(34 "In16.Cu" signal "GND7")
		(2 "B.Cu" signal "BOTTOM")
		(9 "F.Adhes" user "F.Adhesive")
		(11 "B.Adhes" user "B.Adhesive")
		(13 "F.Paste" user "Package Geometry/Pastemask Top")
		(15 "B.Paste" user "Package Geometry/Pastemask Bottom")
		(5 "F.SilkS" user "Ref Des/Silkscreen Top")
		(7 "B.SilkS" user "Ref Des/Silkscreen Bottom")
		(1 "F.Mask" user "Board Geometry/Soldermask Top")
		(3 "B.Mask" user "Board Geometry/Soldermask Bottom")
		(17 "Dwgs.User" user "User.Drawings")
		(19 "Cmts.User" user "User.Comments")
		(21 "Eco1.User" user "User.Eco1")
		(23 "Eco2.User" user "User.Eco2")
		(25 "Edge.Cuts" user "Board Geometry/Outline")
		(27 "Margin" user)
		(31 "F.CrtYd" user "Package Geometry/Place Bound Top")
		(29 "B.CrtYd" user "Package Geometry/Place Bound Bottom")
		(35 "F.Fab" user "Ref Des/Assembly Top")
		(33 "B.Fab" user "Ref Des/Assembly Bottom")
	)
	(footprint ""
		(layer "F.Cu")
		(at 22.479 -367.919)
		(property "Reference" "R1494"
			(at 0 0 0)
			(layer "F.SilkS")
			(hide yes)
			(effects
				(font
					(size 1.27 1.27)
				)
			)
		)
		(property "Value" ""
			(at 0 0 0)
			(layer "F.Fab")
			(effects
				(font
					(size 1.27 1.27)
				)
			)
		)
		(duplicate_pad_numbers_are_jumpers no)
		(fp_line
			(start -0.7874 -0.4064)
			(end 0.7874 -0.4064)
			(stroke
				(width 0.1524)
				(type default)
			)
			(layer "F.SilkS")
		)
		(fp_line
			(start -0.7874 0.4064)
			(end -0.7874 -0.4064)
			(stroke
				(width 0.1524)
				(type default)
			)
			(layer "F.SilkS")
		)
		(fp_line
			(start 0.7874 -0.4064)
			(end 0.7874 0.4064)
			(stroke
				(width 0.1524)
				(type default)
			)
			(layer "F.SilkS")
		)
		(fp_line
			(start 0.7874 0.4064)
			(end -0.7874 0.4064)
			(stroke
				(width 0.1524)
				(type default)
			)
			(layer "F.SilkS")
		)
		(fp_line
			(start -0.67945 -0.305054)
			(end -0.12065 -0.305054)
			(stroke
				(width 0.1)
				(type default)
			)
			(layer "F.Fab")
		)
		(fp_line
			(start -0.67945 0.3048)
			(end -0.67945 -0.305054)
			(stroke
				(width 0.1)
				(type default)
			)
			(layer "F.Fab")
		)
		(fp_line
			(start -0.12065 -0.305054)
			(end -0.12065 -0.2794)
			(stroke
				(width 0.1)
				(type default)
			)
			(layer "F.Fab")
		)
		(fp_line
			(start -0.12065 -0.2794)
			(end 0.12065 -0.2794)
			(stroke
				(width 0.1)
				(type default)
			)
			(layer "F.Fab")
		)
		(fp_line
			(start -0.12065 0.2794)
			(end -0.12065 0.3048)
			(stroke
				(width 0.1)
				(type default)
			)
			(layer "F.Fab")
		)
		(fp_line
			(start -0.12065 0.3048)
			(end -0.67945 0.3048)
			(stroke
				(width 0.1)
				(type default)
			)
			(layer "F.Fab")
		)
		(fp_line
			(start 0.120396 0.2794)
			(end -0.12065 0.2794)
			(stroke
				(width 0.1)
				(type default)
			)
			(layer "F.Fab")
		)
		(fp_line
			(start 0.120396 0.3048)
			(end 0.120396 0.2794)
			(stroke
				(width 0.1)
				(type default)
			)
			(layer "F.Fab")
		)
		(fp_line
			(start 0.12065 -0.3048)
			(end 0.67945 -0.3048)
			(stroke
				(width 0.1)
				(type default)
			)
			(layer "F.Fab")
		)
		(fp_line
			(start 0.12065 -0.2794)
			(end 0.12065 -0.3048)
			(stroke
				(width 0.1)
				(type default)
			)
			(layer "F.Fab")
		)
		(fp_line
			(start 0.67945 -0.3048)
			(end 0.67945 0.3048)
			(stroke
				(width 0.1)
				(type default)
			)
			(layer "F.Fab")
		)
		(fp_line
			(start 0.67945 0.3048)
			(end 0.120396 0.3048)
			(stroke
				(width 0.1)
				(type default)
			)
			(layer "F.Fab")
		)
		(pad "1" smd circle
			(at -0.40005 0)
			(size 0 0)
			(layers "F.Cu" "F.Mask" "F.Paste")
			(net "SMB_VR_3V3STBY_SDA")
		)
		(pad "2" smd circle
			(at 0.40005 0)
			(size 0 0)
			(layers "F.Cu" "F.Mask" "F.Paste")
			(net "SMB_SCM_2_R1_SDA")
		)
	)
	(footprint ""
		(layer "F.Cu")
		(at 468.950294 -43.252898 180)
		(property "Reference" "R561"
			(at 0 0 180)
			(layer "F.SilkS")
			(hide yes)
			(effects
				(font
					(size 1.27 1.27)
				)
			)
		)
		(property "Value" ""
			(at 0 0 180)
			(layer "F.Fab")
			(effects
				(font
					(size 1.27 1.27)
				)
			)
		)
		(duplicate_pad_numbers_are_jumpers no)
		(fp_line
			(start 0.7874 0.4064)
			(end -0.7874 0.4064)
			(stroke
				(width 0.1524)
				(type default)
			)
			(layer "F.SilkS")
		)
		(fp_line
			(start 0.7874 -0.4064)
			(end 0.7874 0.4064)
			(stroke
				(width 0.1524)
				(type default)
			)
			(layer "F.SilkS")
		)
		(fp_line
			(start -0.7874 0.4064)
			(end -0.7874 -0.4064)
			(stroke
				(width 0.1524)
				(type default)
			)
			(layer "F.SilkS")
		)
		(fp_line
			(start -0.7874 -0.4064)
			(end 0.7874 -0.4064)
			(stroke
				(width 0.1524)
				(type default)
			)
			(layer "F.SilkS")
		)
		(fp_line
			(start 0.67945 0.3048)
			(end 0.120396 0.3048)
			(stroke
				(width 0.1)
				(type default)
			)
			(layer "F.Fab")
		)
		(fp_line
			(start 0.67945 -0.3048)
			(end 0.67945 0.3048)
			(stroke
				(width 0.1)
				(type default)
			)
			(layer "F.Fab")
		)
		(fp_line
			(start 0.12065 -0.2794)
			(end 0.12065 -0.3048)
			(stroke
				(width 0.1)
				(type default)
			)
			(layer "F.Fab")
		)
		(fp_line
			(start 0.12065 -0.3048)
			(end 0.67945 -0.3048)
			(stroke
				(width 0.1)
				(type default)
			)
			(layer "F.Fab")
		)
		(fp_line
			(start 0.120396 0.3048)
			(end 0.120396 0.2794)
			(stroke
				(width 0.1)
				(type default)
			)
			(layer "F.Fab")
		)
		(fp_line
			(start 0.120396 0.2794)
			(end -0.12065 0.2794)
			(stroke
				(width 0.1)
				(type default)
			)
			(layer "F.Fab")
		)
		(fp_line
			(start -0.12065 0.3048)
			(end -0.67945 0.3048)
			(stroke
				(width 0.1)
				(type default)
			)
			(layer "F.Fab")
		)
		(fp_line
			(start -0.12065 0.2794)
			(end -0.12065 0.3048)
			(stroke
				(width 0.1)
				(type default)
			)
			(layer "F.Fab")
		)
		(fp_line
			(start -0.12065 -0.2794)
			(end 0.12065 -0.2794)
			(stroke
				(width 0.1)
				(type default)
			)
			(layer "F.Fab")
		)
		(fp_line
			(start -0.12065 -0.305054)
			(end -0.12065 -0.2794)
			(stroke
				(width 0.1)
				(type default)
			)
			(layer "F.Fab")
		)
		(fp_line
			(start -0.67945 0.3048)
			(end -0.67945 -0.305054)
			(stroke
				(width 0.1)
				(type default)
			)
			(layer "F.Fab")
		)
		(fp_line
			(start -0.67945 -0.305054)
			(end -0.12065 -0.305054)
			(stroke
				(width 0.1)
				(type default)
			)
			(layer "F.Fab")
		)
		(pad "1" smd circle
			(at -0.40005 0 180)
			(size 0 0)
			(layers "F.Cu" "F.Mask" "F.Paste")
			(net "P12V_OCP_SFF_BUF_EN_R")
		)
		(pad "2" smd circle
			(at 0.40005 0 180)
			(size 0 0)
			(layers "F.Cu" "F.Mask" "F.Paste")
			(net "P12V_OCP_EN_1_R")
		)
	)
)
